# BASEBOARD_FAB2 (Tioga Pass) — schematic netlist excerpt (pin names and nets, part order shuffled) for the footprints in the layout excerpt that follows; sources: Cadence DE-HDL packaged netlist, KiCad conversion of Wiwynn_Tioga_Pass_MB.brd

J6M1  SCONN288_H44441003  SCONN  pkg PIP  page 50
  \12v\(1)  = P12V_NVDIMM_DEF
  VSS(93)  = GND
  DQ(4)  = M_D_DQ<4>
  VSS(92)  = GND
  DQ(0)  = M_D_DQ<0>
  VSS(91)  = GND
  DQS9P  = M_D_DQS_DP<9>
  DQS9N  = M_D_DQS_DN<9>
  VSS(90)  = GND
  DQ(6)  = M_D_DQ<6>
  VSS(89)  = GND
  DQ(2)  = M_D_DQ<2>
  VSS(88)  = GND
  DQ(12)  = M_D_DQ<12>
  VSS(87)  = GND
  DQ(8)  = M_D_DQ<8>
  VSS(86)  = GND
  DQS10P  = M_D_DQS_DP<10>
  DQS10N  = M_D_DQS_DN<10>
  VSS(85)  = GND
  DQ(14)  = M_D_DQ<14>
  VSS(84)  = GND
  DQ(10)  = M_D_DQ<10>
  VSS(83)  = GND
  DQ(20)  = M_D_DQ<20>
  VSS(82)  = GND
  DQ(16)  = M_D_DQ<16>
  VSS(81)  = GND
  DQS11P  = M_D_DQS_DP<11>
  DQS11N  = M_D_DQS_DN<11>
  VSS(80)  = GND
  DQ(22)  = M_D_DQ<22>
  VSS(79)  = GND
  DQ(18)  = M_D_DQ<18>
  VSS(78)  = GND
  DQ(28)  = M_D_DQ<28>
  VSS(77)  = GND
  DQ(24)  = M_D_DQ<24>
  VSS(76)  = GND
  DQS12P  = M_D_DQS_DP<12>
  DQS12N  = M_D_DQS_DN<12>
  VSS(75)  = GND
  DQ(30)  = M_D_DQ<30>
  VSS(74)  = GND
  DQ(26)  = M_D_DQ<26>
  VSS(73)  = GND
  CB(4)  = M_D_ECC<4>
  VSS(72)  = GND
  CB(0)  = M_D_ECC<0>
  VSS(71)  = GND
  DQS17P  = M_D_DQS_DP<17>
  DQS17N  = M_D_DQS_DN<17>
  VSS(70)  = GND
  CB(6)  = M_D_ECC<6>
  VSS(69)  = GND
  CB(2)  = M_D_ECC<2>
  VSS(68)  = GND
  RESET_N  = M_DEF_RST_N
  VDD(25)  = PVDDQ_DEF
  CKE(0)  = M_D_CKE<2>
  VDD(24)  = PVDDQ_DEF
  ACT_N  = M_D_ACT_N
  BG(0)  = M_D_BG<0>
  VDD(23)  = PVDDQ_DEF
  A12  = M_D_MA<12>
  A9  = M_D_MA<9>
  VDD(22)  = PVDDQ_DEF
  A8  = M_D_MA<8>
  A6  = M_D_MA<6>
  VDD(21)  = PVDDQ_DEF
  A3  = M_D_MA<3>
  A1  = M_D_MA<1>
  VDD(20)  = PVDDQ_DEF
  CK0P  = M_D_CLK_DP<2>
  CK0N  = M_D_CLK_DN<2>
  VDD(19)  = PVDDQ_DEF
  VTT(1)  = PVTT_DEF
  EVENT_N  = FM_DIMM_EVENT_COD_N
  A0  = M_D_MA<0>
  VDD(18)  = PVDDQ_DEF
  BA(0)  = M_D_BA<0>
  A16_RAS_N  = M_D_MA<16>
  VDD(17)  = PVDDQ_DEF
  S0_N  = M_D_CS_N<4>
  VDD(16)  = PVDDQ_DEF
  A15_CAS_N  = M_D_MA<15>
  ODT(0)  = M_D_ODT<2>
  VDD(15)  = PVDDQ_DEF
  S1_N  = M_D_CS_N<5>
  VDD(14)  = PVDDQ_DEF
  ODT(1)  = M_D_ODT<3>
  VDD(13)  = PVDDQ_DEF
  S2_N_C(0)  = M_D_CS_N<6>
  VSS(67)  = GND
  DQ(36)  = M_D_DQ<36>
  VSS(66)  = GND
  DQ(32)  = M_D_DQ<32>
  VSS(65)  = GND
  DQS13P  = M_D_DQS_DP<13>
  DQS13N  = M_D_DQS_DN<13>
  VSS(64)  = GND
  DQ(38)  = M_D_DQ<38>
  VSS(63)  = GND
  DQ(34)  = M_D_DQ<34>
  VSS(62)  = GND
  DQ(44)  = M_D_DQ<44>
  VSS(61)  = GND
  DQ(40)  = M_D_DQ<40>
  VSS(60)  = GND
  DQS14P  = M_D_DQS_DP<14>
  DQS14N  = M_D_DQS_DN<14>
  VSS(59)  = GND
  DQ(46)  = M_D_DQ<46>
  VSS(58)  = GND
  DQ(42)  = M_D_DQ<42>
  VSS(57)  = GND
  DQ(52)  = M_D_DQ<52>
  VSS(56)  = GND
  DQ(48)  = M_D_DQ<48>
  VSS(55)  = GND
  DQS15P  = M_D_DQS_DP<15>
  DQS15N  = M_D_DQS_DN<15>
  VSS(54)  = GND
  DQ(54)  = M_D_DQ<54>
  VSS(53)  = GND
  DQ(50)  = M_D_DQ<50>
  VSS(52)  = GND
  DQ(60)  = M_D_DQ<60>
  VSS(51)  = GND
  DQ(56)  = M_D_DQ<56>
  VSS(50)  = GND
  DQS16P  = M_D_DQS_DP<16>
  DQS16N  = M_D_DQS_DN<16>
  VSS(49)  = GND
  DQ(62)  = M_D_DQ<62>
  VSS(48)  = GND
  DQ(58)  = M_D_DQ<58>
  VSS(47)  = GND
  SA(0)  = PVPP_DEF
  SA(1)  = GND
  SCL  = SMB_DDR_DEF_VPP_SCL
  VPP(4)  = PVPP_DEF
  VPP(3)  = PVPP_DEF
  RFU(2)  = TP_CH_D_DIMM_D1_RFU_2
  \12v\(0)  = P12V_NVDIMM_DEF
  VREFCA  = M_D_VREF
  VSS(46)  = GND
  DQ(5)  = M_D_DQ<5>
  VSS(45)  = GND
  DQ(1)  = M_D_DQ<1>
  VSS(44)  = GND
  DQS0N  = M_D_DQS_DN<0>
  DQS0P  = M_D_DQS_DP<0>
  VSS(43)  = GND
  DQ(7)  = M_D_DQ<7>
  VSS(42)  = GND
  DQ(3)  = M_D_DQ<3>
  VSS(41)  = GND
  DQ(13)  = M_D_DQ<13>
  VSS(40)  = GND
  DQ(9)  = M_D_DQ<9>
  VSS(39)  = GND
  DQS1N  = M_D_DQS_DN<1>
  DQS1P  = M_D_DQS_DP<1>
  VSS(38)  = GND
  DQ(15)  = M_D_DQ<15>
  VSS(37)  = GND
  DQ(11)  = M_D_DQ<11>
  VSS(36)  = GND
  DQ(21)  = M_D_DQ<21>
  VSS(35)  = GND
  DQ(17)  = M_D_DQ<17>
  VSS(34)  = GND
  DQS2N  = M_D_DQS_DN<2>
  DQS2P  = M_D_DQS_DP<2>
  VSS(33)  = GND
  DQ(23)  = M_D_DQ<23>
  VSS(32)  = GND
  DQ(19)  = M_D_DQ<19>
  VSS(31)  = GND
  DQ(29)  = M_D_DQ<29>
  VSS(30)  = GND
  DQ(25)  = M_D_DQ<25>
  VSS(29)  = GND
  DQS3N  = M_D_DQS_DN<3>
  DQS3P  = M_D_DQS_DP<3>
  VSS(28)  = GND
  DQ(31)  = M_D_DQ<31>
  VSS(27)  = GND
  DQ(27)  = M_D_DQ<27>
  VSS(26)  = GND
  CB(5)  = M_D_ECC<5>
  VSS(25)  = GND
  CB(1)  = M_D_ECC<1>
  VSS(24)  = GND
  DQS8N  = M_D_DQS_DN<8>
  DQS8P  = M_D_DQS_DP<8>
  VSS(23)  = GND
  CB(7)  = M_D_ECC<7>
  VSS(22)  = GND
  CB(3)  = M_D_ECC<3>
  VSS(21)  = GND
  CKE(1)  = M_D_CKE<3>
  VDD(12)  = PVDDQ_DEF
  RFU(0)  = TP_CH_D_DIMM_D1_RFU_0
  VDD(11)  = PVDDQ_DEF
  BG(1)  = M_D_BG<1>
  ALERT_N  = M_D_ALERT_N
  VDD(10)  = PVDDQ_DEF
  A11  = M_D_MA<11>
  A7  = M_D_MA<7>
  VDD(9)  = PVDDQ_DEF
  A5  = M_D_MA<5>
  A4  = M_D_MA<4>
  VDD(8)  = PVDDQ_DEF
  A2  = M_D_MA<2>
  VDD(7)  = PVDDQ_DEF
  CK1P  = M_D_CLK_DP<3>
  CK1N  = M_D_CLK_DN<3>
  VDD(6)  = PVDDQ_DEF
  VTT(0)  = PVTT_DEF
  PAR  = M_D_PAR
  VDD(5)  = PVDDQ_DEF
  BA(1)  = M_D_BA<1>
  A10  = M_D_MA<10>
  VDD(4)  = PVDDQ_DEF
  RFU(1)  = TP_CH_D_DIMM_D1_RFU_1
  A14_WE_N  = M_D_MA<14>
  VDD(3)  = PVDDQ_DEF
  SAVE_N_NC  = FM_ADR_COMPLETE_DEF_N
  VDD(2)  = PVDDQ_DEF
  A13  = M_D_MA<13>
  VDD(1)  = PVDDQ_DEF
  A17  = M_D_MA<17>
  C(2)  = M_D_C<2>
  VDD(0)  = PVDDQ_DEF
  S3_N_C(1)  = M_D_CS_N<7>
  SA(2)  = GND
  VSS(20)  = GND
  DQ(37)  = M_D_DQ<37>
  VSS(19)  = GND
  DQ(33)  = M_D_DQ<33>
  VSS(18)  = GND
  DQS4N  = M_D_DQS_DN<4>
  DQS4P  = M_D_DQS_DP<4>
  VSS(17)  = GND
  DQ(39)  = M_D_DQ<39>
  VSS(16)  = GND
  DQ(35)  = M_D_DQ<35>
  VSS(15)  = GND
  DQ(45)  = M_D_DQ<45>
  VSS(14)  = GND
  DQ(41)  = M_D_DQ<41>
  VSS(13)  = GND
  DQS5N  = M_D_DQS_DN<5>
  DQS5P  = M_D_DQS_DP<5>
  VSS(12)  = GND
  DQ(47)  = M_D_DQ<47>
  VSS(11)  = GND
  DQ(43)  = M_D_DQ<43>
  VSS(10)  = GND
  DQ(53)  = M_D_DQ<53>
  VSS(9)  = GND
  DQ(49)  = M_D_DQ<49>
  VSS(8)  = GND
  DQS6N  = M_D_DQS_DN<6>
  DQS6P  = M_D_DQS_DP<6>
  VSS(7)  = GND
  DQ(55)  = M_D_DQ<55>
  VSS(6)  = GND
  DQ(51)  = M_D_DQ<51>
  VSS(5)  = GND
  DQ(61)  = M_D_DQ<61>
  VSS(4)  = GND
  DQ(57)  = M_D_DQ<57>
  VSS(3)  = GND
  DQS7N  = M_D_DQS_DN<7>
  DQS7P  = M_D_DQS_DP<7>
  VSS(2)  = GND
  DQ(63)  = M_D_DQ<63>
  VSS(1)  = GND
  DQ(59)  = M_D_DQ<59>
  VSS(0)  = GND
  VDDSPD  = PVPP_DEF
  SDA  = SMB_DDR_DEF_VPP_SDA
  VPP(1)  = PVPP_DEF
  VPP(0)  = PVPP_DEF
  VPP(2)  = PVPP_DEF

(kicad_pcb
	(version 20260206)
	(generator "pcbnew")
	(generator_version "10.0")
	(general
		(thickness 1.6)
		(legacy_teardrops no)
	)
	(paper "A4")
	(title_block
		(title "Wiwynn_Tioga_Pass_MB.brd")
		(comment 1 "Tioga Pass / footprint 3254 of 4770 (J6M1), pads 1-50 of 291")
	)
	(layers
		(0 "F.Cu" signal "TOP")
		(4 "In1.Cu" signal "L2GND")
		(6 "In2.Cu" signal "L3")
		(8 "In3.Cu" signal "L4GND")
		(10 "In4.Cu" signal "L5")
		(12 "In5.Cu" signal "L6GND")
		(14 "In6.Cu" signal "L7VCC")
		(16 "In7.Cu" signal "L8VCC")
		(18 "In8.Cu" signal "L9GND")
		(20 "In9.Cu" signal "L10")
		(22 "In10.Cu" signal "L11GND")
		(24 "In11.Cu" signal "L12")
		(26 "In12.Cu" signal "L13GND")
		(2 "B.Cu" signal "BOTTOM")
		(9 "F.Adhes" user "F.Adhesive")
		(11 "B.Adhes" user "B.Adhesive")
		(13 "F.Paste" user "Package Geometry/Pastemask Top")
		(15 "B.Paste" user "Package Geometry/Pastemask Bottom")
		(5 "F.SilkS" user "Ref Des/Silkscreen Top")
		(7 "B.SilkS" user "Ref Des/Silkscreen Bottom")
		(1 "F.Mask" user "Board Geometry/Soldermask Top")
		(3 "B.Mask" user "Board Geometry/Soldermask Bottom")
		(17 "Dwgs.User" user "User.Drawings")
		(19 "Cmts.User" user "User.Comments")
		(21 "Eco1.User" user "User.Eco1")
		(23 "Eco2.User" user "User.Eco2")
		(25 "Edge.Cuts" user "Board Geometry/Outline")
		(27 "Margin" user)
		(31 "F.CrtYd" user "Package Geometry/Place Bound Top")
		(29 "B.CrtYd" user "Package Geometry/Place Bound Bottom")
		(35 "F.Fab" user "Ref Des/Assembly Top")
		(33 "B.Fab" user "Ref Des/Assembly Bottom")
	)
	(footprint ""
		(layer "B.Cu")
		(at 194.700398 -132.876036 90)
		(property "Reference" "J6M1"
			(at 2.352548 37.96411 0)
			(unlocked yes)
			(layer "B.SilkS")
			(effects
				(font
					(size 0.7874 0.5842)
					(thickness 0.1524)
				)
				(justify left mirror)
			)
		)
		(property "Value" ""
			(at 0 0 90)
			(layer "B.Fab")
			(effects
				(font
					(size 1.27 1.27)
				)
				(justify mirror)
			)
		)
		(duplicate_pad_numbers_are_jumpers no)
		(pad "" thru_hole circle
			(at -2.29997 -5.649976 270)
			(size 2.8194 2.8194)
			(drill 2.4384)
			(layers "*.Cu" "*.Mask")
			(remove_unused_layers no)
			(clearance 0.127)
			(thermal_gap 0.127)
		)
		(pad "" thru_hole oval
			(at -2.29997 68.90004 270)
			(size 2.8194 1.5748)
			(drill oval 2.4384 1.1938)
			(layers "*.Cu" "*.Mask")
			(remove_unused_layers no)
			(clearance 0.127)
			(thermal_gap 0.127)
		)
		(pad "" thru_hole circle
			(at -2.29997 132.299964 270)
			(size 2.8194 2.8194)
			(drill 2.4384)
			(layers "*.Cu" "*.Mask")
			(remove_unused_layers no)
			(clearance 0.127)
			(thermal_gap 0.127)
		)
		(pad "1" smd rect
			(at 0 0 270)
			(size 1.8034 0.508)
			(layers "B.Cu" "B.Mask" "B.Paste")
			(net "P12V_NVDIMM_DEF")
		)
		(pad "2" smd rect
			(at 0 0.849884 270)
			(size 1.8034 0.508)
			(layers "B.Cu" "B.Mask" "B.Paste")
			(net "GND")
		)
		(pad "3" smd rect
			(at 0 1.700022 270)
			(size 1.8034 0.508)
			(layers "B.Cu" "B.Mask" "B.Paste")
			(net "M_D_DQ<4>")
		)
		(pad "4" smd rect
			(at 0 2.549906 270)
			(size 1.8034 0.508)
			(layers "B.Cu" "B.Mask" "B.Paste")
			(net "GND")
		)
		(pad "5" smd rect
			(at 0 3.400044 270)
			(size 1.8034 0.508)
			(layers "B.Cu" "B.Mask" "B.Paste")
			(net "M_D_DQ<0>")
		)
		(pad "6" smd rect
			(at 0 4.249928 270)
			(size 1.8034 0.508)
			(layers "B.Cu" "B.Mask" "B.Paste")
			(net "GND")
		)
		(pad "7" smd rect
			(at 0 5.100066 270)
			(size 1.8034 0.508)
			(layers "B.Cu" "B.Mask" "B.Paste")
			(net "M_D_DQS_DP<9>")
		)
		(pad "8" smd rect
			(at 0 5.94995 270)
			(size 1.8034 0.508)
			(layers "B.Cu" "B.Mask" "B.Paste")
			(net "M_D_DQS_DN<9>")
		)
		(pad "9" smd rect
			(at 0 6.800088 270)
			(size 1.8034 0.508)
			(layers "B.Cu" "B.Mask" "B.Paste")
			(net "GND")
		)
		(pad "10" smd rect
			(at 0 7.649972 270)
			(size 1.8034 0.508)
			(layers "B.Cu" "B.Mask" "B.Paste")
			(net "M_D_DQ<6>")
		)
		(pad "11" smd rect
			(at 0 8.50011 270)
			(size 1.8034 0.508)
			(layers "B.Cu" "B.Mask" "B.Paste")
			(net "GND")
		)
		(pad "12" smd rect
			(at 0 9.349994 270)
			(size 1.8034 0.508)
			(layers "B.Cu" "B.Mask" "B.Paste")
			(net "M_D_DQ<2>")
		)
		(pad "13" smd rect
			(at 0 10.199878 270)
			(size 1.8034 0.508)
			(layers "B.Cu" "B.Mask" "B.Paste")
			(net "GND")
		)
		(pad "14" smd rect
			(at 0 11.050016 270)
			(size 1.8034 0.508)
			(layers "B.Cu" "B.Mask" "B.Paste")
			(net "M_D_DQ<12>")
		)
		(pad "15" smd rect
			(at 0 11.8999 270)
			(size 1.8034 0.508)
			(layers "B.Cu" "B.Mask" "B.Paste")
			(net "GND")
		)
		(pad "16" smd rect
			(at 0 12.750038 270)
			(size 1.8034 0.508)
			(layers "B.Cu" "B.Mask" "B.Paste")
			(net "M_D_DQ<8>")
		)
		(pad "17" smd rect
			(at 0 13.599922 270)
			(size 1.8034 0.508)
			(layers "B.Cu" "B.Mask" "B.Paste")
			(net "GND")
		)
		(pad "18" smd rect
			(at 0 14.45006 270)
			(size 1.8034 0.508)
			(layers "B.Cu" "B.Mask" "B.Paste")
			(net "M_D_DQS_DP<10>")
		)
		(pad "19" smd rect
			(at 0 15.299944 270)
			(size 1.8034 0.508)
			(layers "B.Cu" "B.Mask" "B.Paste")
			(net "M_D_DQS_DN<10>")
		)
		(pad "20" smd rect
			(at 0 16.150082 270)
			(size 1.8034 0.508)
			(layers "B.Cu" "B.Mask" "B.Paste")
			(net "GND")
		)
		(pad "21" smd rect
			(at 0 16.999966 270)
			(size 1.8034 0.508)
			(layers "B.Cu" "B.Mask" "B.Paste")
			(net "M_D_DQ<14>")
		)
		(pad "22" smd rect
			(at 0 17.850104 270)
			(size 1.8034 0.508)
			(layers "B.Cu" "B.Mask" "B.Paste")
			(net "GND")
		)
		(pad "23" smd rect
			(at 0 18.699988 270)
			(size 1.8034 0.508)
			(layers "B.Cu" "B.Mask" "B.Paste")
			(net "M_D_DQ<10>")
		)
		(pad "24" smd rect
			(at 0 19.550126 270)
			(size 1.8034 0.508)
			(layers "B.Cu" "B.Mask" "B.Paste")
			(net "GND")
		)
		(pad "25" smd rect
			(at 0 20.40001 270)
			(size 1.8034 0.508)
			(layers "B.Cu" "B.Mask" "B.Paste")
			(net "M_D_DQ<20>")
		)
		(pad "26" smd rect
			(at 0 21.249894 270)
			(size 1.8034 0.508)
			(layers "B.Cu" "B.Mask" "B.Paste")
			(net "GND")
		)
		(pad "27" smd rect
			(at 0 22.100032 270)
			(size 1.8034 0.508)
			(layers "B.Cu" "B.Mask" "B.Paste")
			(net "M_D_DQ<16>")
		)
		(pad "28" smd rect
			(at 0 22.949916 270)
			(size 1.8034 0.508)
			(layers "B.Cu" "B.Mask" "B.Paste")
			(net "GND")
		)
		(pad "29" smd rect
			(at 0 23.800054 270)
			(size 1.8034 0.508)
			(layers "B.Cu" "B.Mask" "B.Paste")
			(net "M_D_DQS_DP<11>")
		)
		(pad "30" smd rect
			(at 0 24.649938 270)
			(size 1.8034 0.508)
			(layers "B.Cu" "B.Mask" "B.Paste")
			(net "M_D_DQS_DN<11>")
		)
		(pad "31" smd rect
			(at 0 25.500076 270)
			(size 1.8034 0.508)
			(layers "B.Cu" "B.Mask" "B.Paste")
			(net "GND")
		)
		(pad "32" smd rect
			(at 0 26.34996 270)
			(size 1.8034 0.508)
			(layers "B.Cu" "B.Mask" "B.Paste")
			(net "M_D_DQ<22>")
		)
		(pad "33" smd rect
			(at 0 27.200098 270)
			(size 1.8034 0.508)
			(layers "B.Cu" "B.Mask" "B.Paste")
			(net "GND")
		)
		(pad "34" smd rect
			(at 0 28.049982 270)
			(size 1.8034 0.508)
			(layers "B.Cu" "B.Mask" "B.Paste")
			(net "M_D_DQ<18>")
		)
		(pad "35" smd rect
			(at 0 28.90012 270)
			(size 1.8034 0.508)
			(layers "B.Cu" "B.Mask" "B.Paste")
			(net "GND")
		)
		(pad "36" smd rect
			(at 0 29.750004 270)
			(size 1.8034 0.508)
			(layers "B.Cu" "B.Mask" "B.Paste")
			(net "M_D_DQ<28>")
		)
		(pad "37" smd rect
			(at 0 30.599888 270)
			(size 1.8034 0.508)
			(layers "B.Cu" "B.Mask" "B.Paste")
			(net "GND")
		)
		(pad "38" smd rect
			(at 0 31.450026 270)
			(size 1.8034 0.508)
			(layers "B.Cu" "B.Mask" "B.Paste")
			(net "M_D_DQ<24>")
		)
		(pad "39" smd rect
			(at 0 32.29991 270)
			(size 1.8034 0.508)
			(layers "B.Cu" "B.Mask" "B.Paste")
			(net "GND")
		)
		(pad "40" smd rect
			(at 0 33.150048 270)
			(size 1.8034 0.508)
			(layers "B.Cu" "B.Mask" "B.Paste")
			(net "M_D_DQS_DP<12>")
		)
		(pad "41" smd rect
			(at 0 33.999932 270)
			(size 1.8034 0.508)
			(layers "B.Cu" "B.Mask" "B.Paste")
			(net "M_D_DQS_DN<12>")
		)
		(pad "42" smd rect
			(at 0 34.85007 270)
			(size 1.8034 0.508)
			(layers "B.Cu" "B.Mask" "B.Paste")
			(net "GND")
		)
		(pad "43" smd rect
			(at 0 35.699954 270)
			(size 1.8034 0.508)
			(layers "B.Cu" "B.Mask" "B.Paste")
			(net "M_D_DQ<30>")
		)
		(pad "44" smd rect
			(at 0 36.550092 270)
			(size 1.8034 0.508)
			(layers "B.Cu" "B.Mask" "B.Paste")
			(net "GND")
		)
		(pad "45" smd rect
			(at 0 37.399976 270)
			(size 1.8034 0.508)
			(layers "B.Cu" "B.Mask" "B.Paste")
			(net "M_D_DQ<26>")
		)
		(pad "46" smd rect
			(at 0 38.250114 270)
			(size 1.8034 0.508)
			(layers "B.Cu" "B.Mask" "B.Paste")
			(net "GND")
		)
		(pad "47" smd rect
			(at 0 39.099998 270)
			(size 1.8034 0.508)
			(layers "B.Cu" "B.Mask" "B.Paste")
			(net "M_D_ECC<4>")
		)
	)
)
